G04*
G04 #@! TF.GenerationSoftware,Altium Limited,Altium Designer,22.4.2 (48)*
G04*
G04 Layer_Color=32768*
%FSLAX25Y25*%
%MOIN*%
G70*
G04*
G04 #@! TF.SameCoordinates,446674BB-F454-490D-8607-5140536C8ADF*
G04*
G04*
G04 #@! TF.FilePolarity,Positive*
G04*
G01*
G75*
%ADD13C,0.00787*%
D13*
X660138Y-244075D02*
X685532D01*
Y-211043D01*
X660138D02*
X685532D01*
X660138Y-244075D02*
Y-211043D01*
Y-260256D02*
X685532D01*
X660138Y-293287D02*
Y-260256D01*
Y-293287D02*
X685532D01*
Y-260256D01*
X38189Y6890D02*
X42520D01*
Y16732D01*
X38189D02*
X42520D01*
X38189Y6890D02*
Y16732D01*
X31299Y6890D02*
X35630D01*
Y16732D01*
X31299D02*
X35630D01*
X31299Y6890D02*
Y16732D01*
X24409Y6890D02*
X28740D01*
Y16732D01*
X24409D02*
X28740D01*
X24409Y6890D02*
Y16732D01*
X45079Y6890D02*
X49409D01*
Y16732D01*
X45079D02*
X49409D01*
X45079Y6890D02*
Y16732D01*
X80512Y-107677D02*
X84842D01*
X80512Y-118701D02*
Y-107677D01*
Y-118701D02*
X84842D01*
Y-107677D01*
X73425Y-120669D02*
X78150D01*
X73425Y-130118D02*
Y-120669D01*
Y-130118D02*
X78150D01*
Y-120669D01*
X653937Y-62155D02*
Y-55659D01*
X641339D02*
X653937D01*
X641339Y-62155D02*
Y-55659D01*
Y-62155D02*
X653937D01*
X619488Y-24754D02*
Y-18258D01*
X606890D02*
X619488D01*
X606890Y-24754D02*
Y-18258D01*
Y-24754D02*
X619488D01*
X86319Y-88041D02*
X92815D01*
X86319Y-100639D02*
Y-88041D01*
Y-100639D02*
X92815D01*
Y-88041D01*
X119783Y-69734D02*
X126279D01*
X119783Y-82332D02*
Y-69734D01*
Y-82332D02*
X126279D01*
Y-69734D01*
X477953Y-117569D02*
X494488D01*
Y-132135D02*
Y-117569D01*
X477953Y-132135D02*
X494488D01*
X477953D02*
Y-117569D01*
X508661Y-117765D02*
X522835D01*
Y-131939D02*
Y-117765D01*
X508661Y-131939D02*
X522835D01*
X508661D02*
Y-117765D01*
X454528Y-119201D02*
X466732D01*
X454528Y-132472D02*
Y-119201D01*
Y-132472D02*
X466732D01*
Y-119201D01*
M02*
